# T6G (Grand Teton) — schematic netlist excerpt (pin names and nets, part order shuffled) for the footprints in the layout excerpt that follows; sources: Cadence DE-HDL packaged netlist, KiCad conversion of 04192023_DAF0TMB3IC0_F0TG_MB_C_brd_V02_OCP.brd

C621  Q_CAP  1UF 4V 20% X6S  pkg 0201  page 290 : A = P0V9_CPU0_RT1_2A_2D ; B = GND
R3239  Q_RES  33.2 1% CHIP  pkg 0402LF  page 150 : A = SMB_OCP_SFF_3V3AUX_SDA ; B = SMB_OCP_SFF_3V3AUX_SDA_R0
C362  Q_CAP  0.1UF 16V 10% X7R  pkg C0402  page 83 : A = P3V3_AUX ; B = GND

(kicad_pcb
	(version 20260206)
	(generator "pcbnew")
	(generator_version "10.0")
	(general
		(thickness 1.6)
		(legacy_teardrops no)
	)
	(paper "A4")
	(title_block
		(title "04192023_DAF0TMB3IC0_F0TG_MB_C_brd_V02_OCP.brd")
		(comment 1 "Grand Teton / footprints 5642-5644 of 8354")
	)
	(layers
		(0 "F.Cu" signal "TOP")
		(4 "In1.Cu" signal "GND")
		(6 "In2.Cu" signal "IN1")
		(8 "In3.Cu" signal "GND1")
		(10 "In4.Cu" signal "IN2")
		(12 "In5.Cu" signal "GND2")
		(14 "In6.Cu" signal "IN3")
		(16 "In7.Cu" signal "GND3")
		(18 "In8.Cu" signal "VCC")
		(20 "In9.Cu" signal "VCC1")
		(22 "In10.Cu" signal "GND4")
		(24 "In11.Cu" signal "IN4")
		(26 "In12.Cu" signal "GND5")
		(28 "In13.Cu" signal "IN5")
		(30 "In14.Cu" signal "GND6")
		(32 "In15.Cu" signal "IN6")
		(34 "In16.Cu" signal "GND7")
		(2 "B.Cu" signal "BOTTOM")
		(9 "F.Adhes" user "F.Adhesive")
		(11 "B.Adhes" user "B.Adhesive")
		(13 "F.Paste" user "Package Geometry/Pastemask Top")
		(15 "B.Paste" user "Package Geometry/Pastemask Bottom")
		(5 "F.SilkS" user "Ref Des/Silkscreen Top")
		(7 "B.SilkS" user "Ref Des/Silkscreen Bottom")
		(1 "F.Mask" user "Board Geometry/Soldermask Top")
		(3 "B.Mask" user "Board Geometry/Soldermask Bottom")
		(17 "Dwgs.User" user "User.Drawings")
		(19 "Cmts.User" user "User.Comments")
		(21 "Eco1.User" user "User.Eco1")
		(23 "Eco2.User" user "User.Eco2")
		(25 "Edge.Cuts" user "Board Geometry/Outline")
		(27 "Margin" user)
		(31 "F.CrtYd" user "Package Geometry/Place Bound Top")
		(29 "B.CrtYd" user "Package Geometry/Place Bound Bottom")
		(35 "F.Fab" user "Ref Des/Assembly Top")
		(33 "B.Fab" user "Ref Des/Assembly Bottom")
	)
	(footprint ""
		(layer "B.Cu")
		(at 185.458608 -113.462816 90)
		(property "Reference" "C362"
			(at 0 0 90)
			(layer "B.SilkS")
			(hide yes)
			(effects
				(font
					(size 1.27 1.27)
				)
				(justify mirror)
			)
		)
		(property "Value" ""
			(at 0 0 90)
			(layer "B.Fab")
			(effects
				(font
					(size 1.27 1.27)
				)
				(justify mirror)
			)
		)
		(duplicate_pad_numbers_are_jumpers no)
		(fp_line
			(start 0.69215 -0.2921)
			(end -0.69215 -0.2921)
			(stroke
				(width 0.1524)
				(type default)
			)
			(layer "B.SilkS")
		)
		(fp_line
			(start -0.69215 -0.2921)
			(end -0.69215 0.2921)
			(stroke
				(width 0.1524)
				(type default)
			)
			(layer "B.SilkS")
		)
		(fp_line
			(start 0.69215 0.2921)
			(end 0.69215 -0.2921)
			(stroke
				(width 0.1524)
				(type default)
			)
			(layer "B.SilkS")
		)
		(fp_line
			(start -0.69215 0.2921)
			(end 0.69215 0.2921)
			(stroke
				(width 0.1524)
				(type default)
			)
			(layer "B.SilkS")
		)
		(fp_line
			(start 0.51435 -0.2794)
			(end -0.51435 -0.2794)
			(stroke
				(width 0.1)
				(type default)
			)
			(layer "B.Fab")
		)
		(fp_line
			(start -0.51435 -0.2794)
			(end -0.51435 0.2794)
			(stroke
				(width 0.1)
				(type default)
			)
			(layer "B.Fab")
		)
		(fp_line
			(start 0.51435 0.2794)
			(end 0.51435 -0.2794)
			(stroke
				(width 0.1)
				(type default)
			)
			(layer "B.Fab")
		)
		(fp_line
			(start -0.51435 0.2794)
			(end 0.51435 0.2794)
			(stroke
				(width 0.1)
				(type default)
			)
			(layer "B.Fab")
		)
		(pad "1" smd circle
			(at 0.40005 0 270)
			(size 0 0)
			(layers "B.Cu" "B.Mask" "B.Paste")
			(net "P3V3_AUX")
		)
		(pad "2" smd circle
			(at -0.40005 0 270)
			(size 0 0)
			(layers "B.Cu" "B.Mask" "B.Paste")
			(net "GND")
		)
		(zone
			(layer "B.Cu")
			(hatch none 0.5)
			(connect_pads
				(clearance 0)
			)
			(min_thickness 0.25)
			(keepout
				(tracks not_allowed)
				(vias allowed)
				(pads allowed)
				(copperpour not_allowed)
				(footprints allowed)
			)
			(placement
				(enabled no)
				(sheetname "")
			)
			(fill
				(thermal_gap 0.5)
				(thermal_bridge_width 0.5)
				(island_removal_mode 0)
			)
			(polygon
				(pts
					(xy 185.312558 -113.362486) (xy 185.312558 -113.561876) (xy 185.370724 -113.653316) (xy 185.546238 -113.653316)
					(xy 185.604404 -113.561876) (xy 185.604404 -113.362486) (xy 185.546238 -113.272316) (xy 185.370978 -113.272316)
				)
			)
		)
	)
	(footprint ""
		(layer "B.Cu")
		(at 340.705948 -395.148562 90)
		(property "Reference" "C621"
			(at 0 0 90)
			(layer "B.SilkS")
			(hide yes)
			(effects
				(font
					(size 1.27 1.27)
				)
				(justify mirror)
			)
		)
		(property "Value" ""
			(at 0 0 90)
			(layer "B.Fab")
			(effects
				(font
					(size 1.27 1.27)
				)
				(justify mirror)
			)
		)
		(duplicate_pad_numbers_are_jumpers no)
		(fp_line
			(start 0.299974 -0.150114)
			(end -0.299974 -0.150114)
			(stroke
				(width 0.1)
				(type default)
			)
			(layer "B.Fab")
		)
		(fp_line
			(start -0.299974 -0.150114)
			(end -0.299974 0.150114)
			(stroke
				(width 0.1)
				(type default)
			)
			(layer "B.Fab")
		)
		(fp_line
			(start 0.299974 0.150114)
			(end 0.299974 -0.150114)
			(stroke
				(width 0.1)
				(type default)
			)
			(layer "B.Fab")
		)
		(fp_line
			(start -0.299974 0.150114)
			(end 0.299974 0.150114)
			(stroke
				(width 0.1)
				(type default)
			)
			(layer "B.Fab")
		)
		(pad "1" smd rect
			(at 0.2667 0 270)
			(size 0.3048 0.381)
			(layers "B.Cu" "B.Mask" "B.Paste")
			(net "P0V9_CPU0_RT1_2A_2D")
		)
		(pad "2" smd rect
			(at -0.2667 0 270)
			(size 0.3048 0.381)
			(layers "B.Cu" "B.Mask" "B.Paste")
			(net "GND")
		)
	)
	(footprint ""
		(layer "B.Cu")
		(at 182.88254 -20.378166 90)
		(property "Reference" "R3239"
			(at 0 0 90)
			(layer "B.SilkS")
			(hide yes)
			(effects
				(font
					(size 1.27 1.27)
				)
				(justify mirror)
			)
		)
		(property "Value" ""
			(at 0 0 90)
			(layer "B.Fab")
			(effects
				(font
					(size 1.27 1.27)
				)
				(justify mirror)
			)
		)
		(duplicate_pad_numbers_are_jumpers no)
		(fp_line
			(start 0.7874 -0.4064)
			(end -0.7874 -0.4064)
			(stroke
				(width 0.1524)
				(type default)
			)
			(layer "B.SilkS")
		)
		(fp_line
			(start -0.7874 -0.4064)
			(end -0.7874 0.4064)
			(stroke
				(width 0.1524)
				(type default)
			)
			(layer "B.SilkS")
		)
		(fp_line
			(start 0.7874 0.4064)
			(end 0.7874 -0.4064)
			(stroke
				(width 0.1524)
				(type default)
			)
			(layer "B.SilkS")
		)
		(fp_line
			(start -0.7874 0.4064)
			(end 0.7874 0.4064)
			(stroke
				(width 0.1524)
				(type default)
			)
			(layer "B.SilkS")
		)
		(fp_line
			(start 0.67945 -0.305054)
			(end 0.12065 -0.305054)
			(stroke
				(width 0.1)
				(type default)
			)
			(layer "B.Fab")
		)
		(fp_line
			(start 0.12065 -0.305054)
			(end 0.12065 -0.2794)
			(stroke
				(width 0.1)
				(type default)
			)
			(layer "B.Fab")
		)
		(fp_line
			(start -0.12065 -0.3048)
			(end -0.67945 -0.3048)
			(stroke
				(width 0.1)
				(type default)
			)
			(layer "B.Fab")
		)
		(fp_line
			(start -0.67945 -0.3048)
			(end -0.67945 0.3048)
			(stroke
				(width 0.1)
				(type default)
			)
			(layer "B.Fab")
		)
		(fp_line
			(start 0.12065 -0.2794)
			(end -0.12065 -0.2794)
			(stroke
				(width 0.1)
				(type default)
			)
			(layer "B.Fab")
		)
		(fp_line
			(start -0.12065 -0.2794)
			(end -0.12065 -0.3048)
			(stroke
				(width 0.1)
				(type default)
			)
			(layer "B.Fab")
		)
		(fp_line
			(start 0.12065 0.2794)
			(end 0.12065 0.3048)
			(stroke
				(width 0.1)
				(type default)
			)
			(layer "B.Fab")
		)
		(fp_line
			(start -0.120396 0.2794)
			(end 0.12065 0.2794)
			(stroke
				(width 0.1)
				(type default)
			)
			(layer "B.Fab")
		)
		(fp_line
			(start 0.67945 0.3048)
			(end 0.67945 -0.305054)
			(stroke
				(width 0.1)
				(type default)
			)
			(layer "B.Fab")
		)
		(fp_line
			(start 0.12065 0.3048)
			(end 0.67945 0.3048)
			(stroke
				(width 0.1)
				(type default)
			)
			(layer "B.Fab")
		)
		(fp_line
			(start -0.120396 0.3048)
			(end -0.120396 0.2794)
			(stroke
				(width 0.1)
				(type default)
			)
			(layer "B.Fab")
		)
		(fp_line
			(start -0.67945 0.3048)
			(end -0.120396 0.3048)
			(stroke
				(width 0.1)
				(type default)
			)
			(layer "B.Fab")
		)
		(pad "1" smd circle
			(at 0.40005 0 270)
			(size 0 0)
			(layers "B.Cu" "B.Mask" "B.Paste")
			(net "SMB_OCP_SFF_3V3AUX_SDA")
		)
		(pad "2" smd circle
			(at -0.40005 0 270)
			(size 0 0)
			(layers "B.Cu" "B.Mask" "B.Paste")
			(net "SMB_OCP_SFF_3V3AUX_SDA_R0")
		)
	)
)
